(kicad_pcb
	(version 20260206)
	(generator "pcbnew")
	(generator_version "10.0")
	(general
		(thickness 1.6)
		(legacy_teardrops no)
	)
	(paper "A4")
	(title_block
		(title "01162023_DA0F0TEBIF0_F0T_Expander_BD_F_brd_V02_OCP.brd")
		(comment 1 "Grand Teton / footprints 3204-3209 of 9728")
	)
	(layers
		(0 "F.Cu" signal "TOP")
		(4 "In1.Cu" signal "GND")
		(6 "In2.Cu" signal "VCC")
		(8 "In3.Cu" signal "VCC1")
		(10 "In4.Cu" signal "GND1")
		(12 "In5.Cu" signal "IN1")
		(14 "In6.Cu" signal "GND2")
		(16 "In7.Cu" signal "IN2")
		(18 "In8.Cu" signal "GND3")
		(20 "In9.Cu" signal "IN3")
		(22 "In10.Cu" signal "GND4")
		(24 "In11.Cu" signal "IN4")
		(26 "In12.Cu" signal "GND5")
		(28 "In13.Cu" signal "IN5")
		(30 "In14.Cu" signal "GND6")
		(32 "In15.Cu" signal "IN6")
		(34 "In16.Cu" signal "GND7")
		(2 "B.Cu" signal "BOTTOM")
		(9 "F.Adhes" user "F.Adhesive")
		(11 "B.Adhes" user "B.Adhesive")
		(13 "F.Paste" user "Package Geometry/Pastemask Top")
		(15 "B.Paste" user "Package Geometry/Pastemask Bottom")
		(5 "F.SilkS" user "Ref Des/Silkscreen Top")
		(7 "B.SilkS" user "Ref Des/Silkscreen Bottom")
		(1 "F.Mask" user "Board Geometry/Soldermask Top")
		(3 "B.Mask" user "Board Geometry/Soldermask Bottom")
		(17 "Dwgs.User" user "User.Drawings")
		(19 "Cmts.User" user "User.Comments")
		(21 "Eco1.User" user "User.Eco1")
		(23 "Eco2.User" user "User.Eco2")
		(25 "Edge.Cuts" user "Board Geometry/Outline")
		(27 "Margin" user)
		(31 "F.CrtYd" user "Package Geometry/Place Bound Top")
		(29 "B.CrtYd" user "Package Geometry/Place Bound Bottom")
		(35 "F.Fab" user "Ref Des/Assembly Top")
		(33 "B.Fab" user "Ref Des/Assembly Bottom")
	)
	(footprint ""
		(layer "F.Cu")
		(at 368.475006 -48.753014 180)
		(property "Reference" "C333"
			(at 0 0 180)
			(layer "F.SilkS")
			(hide yes)
			(effects
				(font
					(size 1.27 1.27)
				)
			)
		)
		(property "Value" ""
			(at 0 0 180)
			(layer "F.Fab")
			(effects
				(font
					(size 1.27 1.27)
				)
			)
		)
		(duplicate_pad_numbers_are_jumpers no)
		(fp_line
			(start 0.7874 0.4064)
			(end -0.7874 0.4064)
			(stroke
				(width 0.1524)
				(type default)
			)
			(layer "F.SilkS")
		)
		(fp_line
			(start 0.7874 -0.4064)
			(end 0.7874 0.4064)
			(stroke
				(width 0.1524)
				(type default)
			)
			(layer "F.SilkS")
		)
		(fp_line
			(start -0.7874 0.4064)
			(end -0.7874 -0.4064)
			(stroke
				(width 0.1524)
				(type default)
			)
			(layer "F.SilkS")
		)
		(fp_line
			(start -0.7874 -0.4064)
			(end 0.7874 -0.4064)
			(stroke
				(width 0.1524)
				(type default)
			)
			(layer "F.SilkS")
		)
		(fp_line
			(start 0.67945 0.3048)
			(end 0.120396 0.3048)
			(stroke
				(width 0.1)
				(type default)
			)
			(layer "F.Fab")
		)
		(fp_line
			(start 0.67945 -0.3048)
			(end 0.67945 0.3048)
			(stroke
				(width 0.1)
				(type default)
			)
			(layer "F.Fab")
		)
		(fp_line
			(start 0.12065 -0.2794)
			(end 0.12065 -0.3048)
			(stroke
				(width 0.1)
				(type default)
			)
			(layer "F.Fab")
		)
		(fp_line
			(start 0.12065 -0.3048)
			(end 0.67945 -0.3048)
			(stroke
				(width 0.1)
				(type default)
			)
			(layer "F.Fab")
		)
		(fp_line
			(start 0.120396 0.3048)
			(end 0.120396 0.2794)
			(stroke
				(width 0.1)
				(type default)
			)
			(layer "F.Fab")
		)
		(fp_line
			(start 0.120396 0.2794)
			(end -0.12065 0.2794)
			(stroke
				(width 0.1)
				(type default)
			)
			(layer "F.Fab")
		)
		(fp_line
			(start -0.12065 0.3048)
			(end -0.67945 0.3048)
			(stroke
				(width 0.1)
				(type default)
			)
			(layer "F.Fab")
		)
		(fp_line
			(start -0.12065 0.2794)
			(end -0.12065 0.3048)
			(stroke
				(width 0.1)
				(type default)
			)
			(layer "F.Fab")
		)
		(fp_line
			(start -0.12065 -0.2794)
			(end 0.12065 -0.2794)
			(stroke
				(width 0.1)
				(type default)
			)
			(layer "F.Fab")
		)
		(fp_line
			(start -0.12065 -0.305054)
			(end -0.12065 -0.2794)
			(stroke
				(width 0.1)
				(type default)
			)
			(layer "F.Fab")
		)
		(fp_line
			(start -0.67945 0.3048)
			(end -0.67945 -0.305054)
			(stroke
				(width 0.1)
				(type default)
			)
			(layer "F.Fab")
		)
		(fp_line
			(start -0.67945 -0.305054)
			(end -0.12065 -0.305054)
			(stroke
				(width 0.1)
				(type default)
			)
			(layer "F.Fab")
		)
		(pad "1" smd circle
			(at -0.40005 0 180)
			(size 0 0)
			(layers "F.Cu" "F.Mask" "F.Paste")
			(net "P3V3_AUX")
		)
		(pad "2" smd circle
			(at 0.40005 0 180)
			(size 0 0)
			(layers "F.Cu" "F.Mask" "F.Paste")
			(net "GND")
		)
	)
	(footprint ""
		(layer "F.Cu")
		(at 378.852684 -83.1088)
		(property "Reference" "R1775"
			(at 0 0 0)
			(layer "F.SilkS")
			(hide yes)
			(effects
				(font
					(size 1.27 1.27)
				)
			)
		)
		(property "Value" ""
			(at 0 0 0)
			(layer "F.Fab")
			(effects
				(font
					(size 1.27 1.27)
				)
			)
		)
		(duplicate_pad_numbers_are_jumpers no)
		(fp_line
			(start -0.7874 -0.4064)
			(end 0.7874 -0.4064)
			(stroke
				(width 0.1524)
				(type default)
			)
			(layer "F.SilkS")
		)
		(fp_line
			(start -0.7874 0.4064)
			(end -0.7874 -0.4064)
			(stroke
				(width 0.1524)
				(type default)
			)
			(layer "F.SilkS")
		)
		(fp_line
			(start 0.7874 -0.4064)
			(end 0.7874 0.4064)
			(stroke
				(width 0.1524)
				(type default)
			)
			(layer "F.SilkS")
		)
		(fp_line
			(start 0.7874 0.4064)
			(end -0.7874 0.4064)
			(stroke
				(width 0.1524)
				(type default)
			)
			(layer "F.SilkS")
		)
		(fp_line
			(start -0.67945 -0.305054)
			(end -0.12065 -0.305054)
			(stroke
				(width 0.1)
				(type default)
			)
			(layer "F.Fab")
		)
		(fp_line
			(start -0.67945 0.3048)
			(end -0.67945 -0.305054)
			(stroke
				(width 0.1)
				(type default)
			)
			(layer "F.Fab")
		)
		(fp_line
			(start -0.12065 -0.305054)
			(end -0.12065 -0.2794)
			(stroke
				(width 0.1)
				(type default)
			)
			(layer "F.Fab")
		)
		(fp_line
			(start -0.12065 -0.2794)
			(end 0.12065 -0.2794)
			(stroke
				(width 0.1)
				(type default)
			)
			(layer "F.Fab")
		)
		(fp_line
			(start -0.12065 0.2794)
			(end -0.12065 0.3048)
			(stroke
				(width 0.1)
				(type default)
			)
			(layer "F.Fab")
		)
		(fp_line
			(start -0.12065 0.3048)
			(end -0.67945 0.3048)
			(stroke
				(width 0.1)
				(type default)
			)
			(layer "F.Fab")
		)
		(fp_line
			(start 0.120396 0.2794)
			(end -0.12065 0.2794)
			(stroke
				(width 0.1)
				(type default)
			)
			(layer "F.Fab")
		)
		(fp_line
			(start 0.120396 0.3048)
			(end 0.120396 0.2794)
			(stroke
				(width 0.1)
				(type default)
			)
			(layer "F.Fab")
		)
		(fp_line
			(start 0.12065 -0.3048)
			(end 0.67945 -0.3048)
			(stroke
				(width 0.1)
				(type default)
			)
			(layer "F.Fab")
		)
		(fp_line
			(start 0.12065 -0.2794)
			(end 0.12065 -0.3048)
			(stroke
				(width 0.1)
				(type default)
			)
			(layer "F.Fab")
		)
		(fp_line
			(start 0.67945 -0.3048)
			(end 0.67945 0.3048)
			(stroke
				(width 0.1)
				(type default)
			)
			(layer "F.Fab")
		)
		(fp_line
			(start 0.67945 0.3048)
			(end 0.120396 0.3048)
			(stroke
				(width 0.1)
				(type default)
			)
			(layer "F.Fab")
		)
		(pad "1" smd circle
			(at -0.40005 0)
			(size 0 0)
			(layers "F.Cu" "F.Mask" "F.Paste")
			(net "SMB_BIC_I2C6_MUX_THERMAL_R_SCL")
		)
		(pad "2" smd circle
			(at 0.40005 0)
			(size 0 0)
			(layers "F.Cu" "F.Mask" "F.Paste")
			(net "SMB_BIC_I2C6_MUX_THERMAL_SCL")
		)
	)
	(footprint ""
		(layer "F.Cu")
		(at 136.445244 -88.956642 180)
		(property "Reference" "R1578"
			(at 0 0 180)
			(layer "F.SilkS")
			(hide yes)
			(effects
				(font
					(size 1.27 1.27)
				)
			)
		)
		(property "Value" ""
			(at 0 0 180)
			(layer "F.Fab")
			(effects
				(font
					(size 1.27 1.27)
				)
			)
		)
		(duplicate_pad_numbers_are_jumpers no)
		(fp_line
			(start 0.7874 0.4064)
			(end -0.7874 0.4064)
			(stroke
				(width 0.1524)
				(type default)
			)
			(layer "F.SilkS")
		)
		(fp_line
			(start 0.7874 -0.4064)
			(end 0.7874 0.4064)
			(stroke
				(width 0.1524)
				(type default)
			)
			(layer "F.SilkS")
		)
		(fp_line
			(start -0.7874 0.4064)
			(end -0.7874 -0.4064)
			(stroke
				(width 0.1524)
				(type default)
			)
			(layer "F.SilkS")
		)
		(fp_line
			(start -0.7874 -0.4064)
			(end 0.7874 -0.4064)
			(stroke
				(width 0.1524)
				(type default)
			)
			(layer "F.SilkS")
		)
		(fp_line
			(start 0.67945 0.3048)
			(end 0.120396 0.3048)
			(stroke
				(width 0.1)
				(type default)
			)
			(layer "F.Fab")
		)
		(fp_line
			(start 0.67945 -0.3048)
			(end 0.67945 0.3048)
			(stroke
				(width 0.1)
				(type default)
			)
			(layer "F.Fab")
		)
		(fp_line
			(start 0.12065 -0.2794)
			(end 0.12065 -0.3048)
			(stroke
				(width 0.1)
				(type default)
			)
			(layer "F.Fab")
		)
		(fp_line
			(start 0.12065 -0.3048)
			(end 0.67945 -0.3048)
			(stroke
				(width 0.1)
				(type default)
			)
			(layer "F.Fab")
		)
		(fp_line
			(start 0.120396 0.3048)
			(end 0.120396 0.2794)
			(stroke
				(width 0.1)
				(type default)
			)
			(layer "F.Fab")
		)
		(fp_line
			(start 0.120396 0.2794)
			(end -0.12065 0.2794)
			(stroke
				(width 0.1)
				(type default)
			)
			(layer "F.Fab")
		)
		(fp_line
			(start -0.12065 0.3048)
			(end -0.67945 0.3048)
			(stroke
				(width 0.1)
				(type default)
			)
			(layer "F.Fab")
		)
		(fp_line
			(start -0.12065 0.2794)
			(end -0.12065 0.3048)
			(stroke
				(width 0.1)
				(type default)
			)
			(layer "F.Fab")
		)
		(fp_line
			(start -0.12065 -0.2794)
			(end 0.12065 -0.2794)
			(stroke
				(width 0.1)
				(type default)
			)
			(layer "F.Fab")
		)
		(fp_line
			(start -0.12065 -0.305054)
			(end -0.12065 -0.2794)
			(stroke
				(width 0.1)
				(type default)
			)
			(layer "F.Fab")
		)
		(fp_line
			(start -0.67945 0.3048)
			(end -0.67945 -0.305054)
			(stroke
				(width 0.1)
				(type default)
			)
			(layer "F.Fab")
		)
		(fp_line
			(start -0.67945 -0.305054)
			(end -0.12065 -0.305054)
			(stroke
				(width 0.1)
				(type default)
			)
			(layer "F.Fab")
		)
		(pad "1" smd circle
			(at -0.40005 0 180)
			(size 0 0)
			(layers "F.Cu" "F.Mask" "F.Paste")
			(net "SMB_BIC_I2C9_MUX0_SSD4_R_SCL")
		)
		(pad "2" smd circle
			(at 0.40005 0 180)
			(size 0 0)
			(layers "F.Cu" "F.Mask" "F.Paste")
			(net "SMB_BIC_I2C9_MUX0_SSD4_SCL")
		)
	)
	(footprint ""
		(layer "F.Cu")
		(at 154.707844 -156.3624 180)
		(property "Reference" "R115"
			(at 0 0 180)
			(layer "F.SilkS")
			(hide yes)
			(effects
				(font
					(size 1.27 1.27)
				)
			)
		)
		(property "Value" ""
			(at 0 0 180)
			(layer "F.Fab")
			(effects
				(font
					(size 1.27 1.27)
				)
			)
		)
		(duplicate_pad_numbers_are_jumpers no)
		(fp_line
			(start 0.7874 0.4064)
			(end -0.7874 0.4064)
			(stroke
				(width 0.1524)
				(type default)
			)
			(layer "F.SilkS")
		)
		(fp_line
			(start 0.7874 -0.4064)
			(end 0.7874 0.4064)
			(stroke
				(width 0.1524)
				(type default)
			)
			(layer "F.SilkS")
		)
		(fp_line
			(start -0.7874 0.4064)
			(end -0.7874 -0.4064)
			(stroke
				(width 0.1524)
				(type default)
			)
			(layer "F.SilkS")
		)
		(fp_line
			(start -0.7874 -0.4064)
			(end 0.7874 -0.4064)
			(stroke
				(width 0.1524)
				(type default)
			)
			(layer "F.SilkS")
		)
		(fp_line
			(start 0.67945 0.3048)
			(end 0.120396 0.3048)
			(stroke
				(width 0.1)
				(type default)
			)
			(layer "F.Fab")
		)
		(fp_line
			(start 0.67945 -0.3048)
			(end 0.67945 0.3048)
			(stroke
				(width 0.1)
				(type default)
			)
			(layer "F.Fab")
		)
		(fp_line
			(start 0.12065 -0.2794)
			(end 0.12065 -0.3048)
			(stroke
				(width 0.1)
				(type default)
			)
			(layer "F.Fab")
		)
		(fp_line
			(start 0.12065 -0.3048)
			(end 0.67945 -0.3048)
			(stroke
				(width 0.1)
				(type default)
			)
			(layer "F.Fab")
		)
		(fp_line
			(start 0.120396 0.3048)
			(end 0.120396 0.2794)
			(stroke
				(width 0.1)
				(type default)
			)
			(layer "F.Fab")
		)
		(fp_line
			(start 0.120396 0.2794)
			(end -0.12065 0.2794)
			(stroke
				(width 0.1)
				(type default)
			)
			(layer "F.Fab")
		)
		(fp_line
			(start -0.12065 0.3048)
			(end -0.67945 0.3048)
			(stroke
				(width 0.1)
				(type default)
			)
			(layer "F.Fab")
		)
		(fp_line
			(start -0.12065 0.2794)
			(end -0.12065 0.3048)
			(stroke
				(width 0.1)
				(type default)
			)
			(layer "F.Fab")
		)
		(fp_line
			(start -0.12065 -0.2794)
			(end 0.12065 -0.2794)
			(stroke
				(width 0.1)
				(type default)
			)
			(layer "F.Fab")
		)
		(fp_line
			(start -0.12065 -0.305054)
			(end -0.12065 -0.2794)
			(stroke
				(width 0.1)
				(type default)
			)
			(layer "F.Fab")
		)
		(fp_line
			(start -0.67945 0.3048)
			(end -0.67945 -0.305054)
			(stroke
				(width 0.1)
				(type default)
			)
			(layer "F.Fab")
		)
		(fp_line
			(start -0.67945 -0.305054)
			(end -0.12065 -0.305054)
			(stroke
				(width 0.1)
				(type default)
			)
			(layer "F.Fab")
		)
		(pad "1" smd circle
			(at -0.40005 0 180)
			(size 0 0)
			(layers "F.Cu" "F.Mask" "F.Paste")
			(net "NIC2_DATA_OUT")
		)
		(pad "2" smd circle
			(at 0.40005 0 180)
			(size 0 0)
			(layers "F.Cu" "F.Mask" "F.Paste")
			(net "GND")
		)
	)
	(footprint ""
		(layer "F.Cu")
		(at 113.561114 -261.687564 180)
		(property "Reference" "PR84"
			(at 0 0 180)
			(layer "F.SilkS")
			(hide yes)
			(effects
				(font
					(size 1.27 1.27)
				)
			)
		)
		(property "Value" ""
			(at 0 0 180)
			(layer "F.Fab")
			(effects
				(font
					(size 1.27 1.27)
				)
			)
		)
		(duplicate_pad_numbers_are_jumpers no)
		(fp_line
			(start 0.7874 0.4064)
			(end -0.7874 0.4064)
			(stroke
				(width 0.1524)
				(type default)
			)
			(layer "F.SilkS")
		)
		(fp_line
			(start 0.7874 -0.4064)
			(end 0.7874 0.4064)
			(stroke
				(width 0.1524)
				(type default)
			)
			(layer "F.SilkS")
		)
		(fp_line
			(start -0.7874 0.4064)
			(end -0.7874 -0.4064)
			(stroke
				(width 0.1524)
				(type default)
			)
			(layer "F.SilkS")
		)
		(fp_line
			(start -0.7874 -0.4064)
			(end 0.7874 -0.4064)
			(stroke
				(width 0.1524)
				(type default)
			)
			(layer "F.SilkS")
		)
		(fp_line
			(start 0.67945 0.3048)
			(end 0.120396 0.3048)
			(stroke
				(width 0.1)
				(type default)
			)
			(layer "F.Fab")
		)
		(fp_line
			(start 0.67945 -0.3048)
			(end 0.67945 0.3048)
			(stroke
				(width 0.1)
				(type default)
			)
			(layer "F.Fab")
		)
		(fp_line
			(start 0.12065 -0.2794)
			(end 0.12065 -0.3048)
			(stroke
				(width 0.1)
				(type default)
			)
			(layer "F.Fab")
		)
		(fp_line
			(start 0.12065 -0.3048)
			(end 0.67945 -0.3048)
			(stroke
				(width 0.1)
				(type default)
			)
			(layer "F.Fab")
		)
		(fp_line
			(start 0.120396 0.3048)
			(end 0.120396 0.2794)
			(stroke
				(width 0.1)
				(type default)
			)
			(layer "F.Fab")
		)
		(fp_line
			(start 0.120396 0.2794)
			(end -0.12065 0.2794)
			(stroke
				(width 0.1)
				(type default)
			)
			(layer "F.Fab")
		)
		(fp_line
			(start -0.12065 0.3048)
			(end -0.67945 0.3048)
			(stroke
				(width 0.1)
				(type default)
			)
			(layer "F.Fab")
		)
		(fp_line
			(start -0.12065 0.2794)
			(end -0.12065 0.3048)
			(stroke
				(width 0.1)
				(type default)
			)
			(layer "F.Fab")
		)
		(fp_line
			(start -0.12065 -0.2794)
			(end 0.12065 -0.2794)
			(stroke
				(width 0.1)
				(type default)
			)
			(layer "F.Fab")
		)
		(fp_line
			(start -0.12065 -0.305054)
			(end -0.12065 -0.2794)
			(stroke
				(width 0.1)
				(type default)
			)
			(layer "F.Fab")
		)
		(fp_line
			(start -0.67945 0.3048)
			(end -0.67945 -0.305054)
			(stroke
				(width 0.1)
				(type default)
			)
			(layer "F.Fab")
		)
		(fp_line
			(start -0.67945 -0.305054)
			(end -0.12065 -0.305054)
			(stroke
				(width 0.1)
				(type default)
			)
			(layer "F.Fab")
		)
		(pad "1" smd circle
			(at -0.40005 0 180)
			(size 0 0)
			(layers "F.Cu" "F.Mask" "F.Paste")
			(net "P0V8_PEX0_VR_CONFIG")
		)
		(pad "2" smd circle
			(at 0.40005 0 180)
			(size 0 0)
			(layers "F.Cu" "F.Mask" "F.Paste")
			(net "GND")
		)
	)
	(footprint ""
		(layer "F.Cu")
		(at 208.286858 -220.79077 90)
		(property "Reference" "C3644"
			(at 0 0 90)
			(layer "F.SilkS")
			(hide yes)
			(effects
				(font
					(size 1.27 1.27)
				)
			)
		)
		(property "Value" ""
			(at 0 0 90)
			(layer "F.Fab")
			(effects
				(font
					(size 1.27 1.27)
				)
			)
		)
		(duplicate_pad_numbers_are_jumpers no)
		(fp_line
			(start 0.7874 -0.4064)
			(end 0.7874 0.4064)
			(stroke
				(width 0.1524)
				(type default)
			)
			(layer "F.SilkS")
		)
		(fp_line
			(start -0.7874 -0.4064)
			(end 0.7874 -0.4064)
			(stroke
				(width 0.1524)
				(type default)
			)
			(layer "F.SilkS")
		)
		(fp_line
			(start 0.7874 0.4064)
			(end -0.7874 0.4064)
			(stroke
				(width 0.1524)
				(type default)
			)
			(layer "F.SilkS")
		)
		(fp_line
			(start -0.7874 0.4064)
			(end -0.7874 -0.4064)
			(stroke
				(width 0.1524)
				(type default)
			)
			(layer "F.SilkS")
		)
		(fp_line
			(start -0.12065 -0.305054)
			(end -0.12065 -0.2794)
			(stroke
				(width 0.1)
				(type default)
			)
			(layer "F.Fab")
		)
		(fp_line
			(start -0.67945 -0.305054)
			(end -0.12065 -0.305054)
			(stroke
				(width 0.1)
				(type default)
			)
			(layer "F.Fab")
		)
		(fp_line
			(start 0.67945 -0.3048)
			(end 0.67945 0.3048)
			(stroke
				(width 0.1)
				(type default)
			)
			(layer "F.Fab")
		)
		(fp_line
			(start 0.12065 -0.3048)
			(end 0.67945 -0.3048)
			(stroke
				(width 0.1)
				(type default)
			)
			(layer "F.Fab")
		)
		(fp_line
			(start 0.12065 -0.2794)
			(end 0.12065 -0.3048)
			(stroke
				(width 0.1)
				(type default)
			)
			(layer "F.Fab")
		)
		(fp_line
			(start -0.12065 -0.2794)
			(end 0.12065 -0.2794)
			(stroke
				(width 0.1)
				(type default)
			)
			(layer "F.Fab")
		)
		(fp_line
			(start 0.120396 0.2794)
			(end -0.12065 0.2794)
			(stroke
				(width 0.1)
				(type default)
			)
			(layer "F.Fab")
		)
		(fp_line
			(start -0.12065 0.2794)
			(end -0.12065 0.3048)
			(stroke
				(width 0.1)
				(type default)
			)
			(layer "F.Fab")
		)
		(fp_line
			(start 0.67945 0.3048)
			(end 0.120396 0.3048)
			(stroke
				(width 0.1)
				(type default)
			)
			(layer "F.Fab")
		)
		(fp_line
			(start 0.120396 0.3048)
			(end 0.120396 0.2794)
			(stroke
				(width 0.1)
				(type default)
			)
			(layer "F.Fab")
		)
		(fp_line
			(start -0.12065 0.3048)
			(end -0.67945 0.3048)
			(stroke
				(width 0.1)
				(type default)
			)
			(layer "F.Fab")
		)
		(fp_line
			(start -0.67945 0.3048)
			(end -0.67945 -0.305054)
			(stroke
				(width 0.1)
				(type default)
			)
			(layer "F.Fab")
		)
		(pad "1" smd circle
			(at -0.40005 0 90)
			(size 0 0)
			(layers "F.Cu" "F.Mask" "F.Paste")
			(net "GND")
		)
		(pad "2" smd circle
			(at 0.40005 0 90)
			(size 0 0)
			(layers "F.Cu" "F.Mask" "F.Paste")
			(net "P3V3_AUX")
		)
	)
)
